# T6G (Grand Teton) — schematic netlist excerpt (pin names and nets, part order shuffled) for the footprints in the layout excerpt that follows; sources: Cadence DE-HDL packaged netlist, KiCad conversion of 04192023_DAF0TMB3IC0_F0TG_MB_C_brd_V02_OCP.brd

C2664  Q_CAP  22UF 4V 20% X6S  pkg C0402  page 75 : A = PVDD18_S5_P1 ; B = GND
C8004  Q_CAP  0.1UF 25V 10% EMPTY  pkg 0402  page 143 : A = OCP_V3_2_PRSNT23_R1_N ; B = GND
C1530  Q_CAP_DIFFBUS  DIFF BUS_0.22UF 6.3V 20% X6S  pkg C0201  page 67 : \1\ = P5E_CPU1_P3_TX_C_DN<8> ; \2\ = P5E_CPU1_P3_TX_DN<8>

(kicad_pcb
	(version 20260206)
	(generator "pcbnew")
	(generator_version "10.0")
	(general
		(thickness 1.6)
		(legacy_teardrops no)
	)
	(paper "A4")
	(title_block
		(title "04192023_DAF0TMB3IC0_F0TG_MB_C_brd_V02_OCP.brd")
		(comment 1 "Grand Teton / footprints 4473-4475 of 8354")
	)
	(layers
		(0 "F.Cu" signal "TOP")
		(4 "In1.Cu" signal "GND")
		(6 "In2.Cu" signal "IN1")
		(8 "In3.Cu" signal "GND1")
		(10 "In4.Cu" signal "IN2")
		(12 "In5.Cu" signal "GND2")
		(14 "In6.Cu" signal "IN3")
		(16 "In7.Cu" signal "GND3")
		(18 "In8.Cu" signal "VCC")
		(20 "In9.Cu" signal "VCC1")
		(22 "In10.Cu" signal "GND4")
		(24 "In11.Cu" signal "IN4")
		(26 "In12.Cu" signal "GND5")
		(28 "In13.Cu" signal "IN5")
		(30 "In14.Cu" signal "GND6")
		(32 "In15.Cu" signal "IN6")
		(34 "In16.Cu" signal "GND7")
		(2 "B.Cu" signal "BOTTOM")
		(9 "F.Adhes" user "F.Adhesive")
		(11 "B.Adhes" user "B.Adhesive")
		(13 "F.Paste" user "Package Geometry/Pastemask Top")
		(15 "B.Paste" user "Package Geometry/Pastemask Bottom")
		(5 "F.SilkS" user "Ref Des/Silkscreen Top")
		(7 "B.SilkS" user "Ref Des/Silkscreen Bottom")
		(1 "F.Mask" user "Board Geometry/Soldermask Top")
		(3 "B.Mask" user "Board Geometry/Soldermask Bottom")
		(17 "Dwgs.User" user "User.Drawings")
		(19 "Cmts.User" user "User.Comments")
		(21 "Eco1.User" user "User.Eco1")
		(23 "Eco2.User" user "User.Eco2")
		(25 "Edge.Cuts" user "Board Geometry/Outline")
		(27 "Margin" user)
		(31 "F.CrtYd" user "Package Geometry/Place Bound Top")
		(29 "B.CrtYd" user "Package Geometry/Place Bound Bottom")
		(35 "F.Fab" user "Ref Des/Assembly Top")
		(33 "B.Fab" user "Ref Des/Assembly Bottom")
	)
	(footprint ""
		(layer "F.Cu")
		(at 13.335 -77.089)
		(property "Reference" "C8004"
			(at 0 0 0)
			(layer "F.SilkS")
			(hide yes)
			(effects
				(font
					(size 1.27 1.27)
				)
			)
		)
		(property "Value" ""
			(at 0 0 0)
			(layer "F.Fab")
			(effects
				(font
					(size 1.27 1.27)
				)
			)
		)
		(duplicate_pad_numbers_are_jumpers no)
		(fp_line
			(start -0.7874 -0.4064)
			(end 0.7874 -0.4064)
			(stroke
				(width 0.1524)
				(type default)
			)
			(layer "F.SilkS")
		)
		(fp_line
			(start -0.7874 0.4064)
			(end -0.7874 -0.4064)
			(stroke
				(width 0.1524)
				(type default)
			)
			(layer "F.SilkS")
		)
		(fp_line
			(start 0.7874 -0.4064)
			(end 0.7874 0.4064)
			(stroke
				(width 0.1524)
				(type default)
			)
			(layer "F.SilkS")
		)
		(fp_line
			(start 0.7874 0.4064)
			(end -0.7874 0.4064)
			(stroke
				(width 0.1524)
				(type default)
			)
			(layer "F.SilkS")
		)
		(fp_line
			(start -0.67945 -0.305054)
			(end -0.12065 -0.305054)
			(stroke
				(width 0.1)
				(type default)
			)
			(layer "F.Fab")
		)
		(fp_line
			(start -0.67945 0.3048)
			(end -0.67945 -0.305054)
			(stroke
				(width 0.1)
				(type default)
			)
			(layer "F.Fab")
		)
		(fp_line
			(start -0.12065 -0.305054)
			(end -0.12065 -0.2794)
			(stroke
				(width 0.1)
				(type default)
			)
			(layer "F.Fab")
		)
		(fp_line
			(start -0.12065 -0.2794)
			(end 0.12065 -0.2794)
			(stroke
				(width 0.1)
				(type default)
			)
			(layer "F.Fab")
		)
		(fp_line
			(start -0.12065 0.2794)
			(end -0.12065 0.3048)
			(stroke
				(width 0.1)
				(type default)
			)
			(layer "F.Fab")
		)
		(fp_line
			(start -0.12065 0.3048)
			(end -0.67945 0.3048)
			(stroke
				(width 0.1)
				(type default)
			)
			(layer "F.Fab")
		)
		(fp_line
			(start 0.120396 0.2794)
			(end -0.12065 0.2794)
			(stroke
				(width 0.1)
				(type default)
			)
			(layer "F.Fab")
		)
		(fp_line
			(start 0.120396 0.3048)
			(end 0.120396 0.2794)
			(stroke
				(width 0.1)
				(type default)
			)
			(layer "F.Fab")
		)
		(fp_line
			(start 0.12065 -0.3048)
			(end 0.67945 -0.3048)
			(stroke
				(width 0.1)
				(type default)
			)
			(layer "F.Fab")
		)
		(fp_line
			(start 0.12065 -0.2794)
			(end 0.12065 -0.3048)
			(stroke
				(width 0.1)
				(type default)
			)
			(layer "F.Fab")
		)
		(fp_line
			(start 0.67945 -0.3048)
			(end 0.67945 0.3048)
			(stroke
				(width 0.1)
				(type default)
			)
			(layer "F.Fab")
		)
		(fp_line
			(start 0.67945 0.3048)
			(end 0.120396 0.3048)
			(stroke
				(width 0.1)
				(type default)
			)
			(layer "F.Fab")
		)
		(pad "1" smd circle
			(at -0.40005 0)
			(size 0 0)
			(layers "F.Cu" "F.Mask" "F.Paste")
			(net "OCP_V3_2_PRSNT23_R1_N")
		)
		(pad "2" smd circle
			(at 0.40005 0)
			(size 0 0)
			(layers "F.Cu" "F.Mask" "F.Paste")
			(net "GND")
		)
	)
	(footprint ""
		(layer "F.Cu")
		(at 108.360464 -257.750564)
		(property "Reference" "C2664"
			(at 0 0 0)
			(layer "F.SilkS")
			(hide yes)
			(effects
				(font
					(size 1.27 1.27)
				)
			)
		)
		(property "Value" ""
			(at 0 0 0)
			(layer "F.Fab")
			(effects
				(font
					(size 1.27 1.27)
				)
			)
		)
		(duplicate_pad_numbers_are_jumpers no)
		(fp_line
			(start -0.7874 -0.4064)
			(end 0.7874 -0.4064)
			(stroke
				(width 0.1524)
				(type default)
			)
			(layer "F.SilkS")
		)
		(fp_line
			(start -0.7874 0.4064)
			(end -0.7874 -0.4064)
			(stroke
				(width 0.1524)
				(type default)
			)
			(layer "F.SilkS")
		)
		(fp_line
			(start 0.7874 -0.4064)
			(end 0.7874 0.4064)
			(stroke
				(width 0.1524)
				(type default)
			)
			(layer "F.SilkS")
		)
		(fp_line
			(start 0.7874 0.4064)
			(end -0.7874 0.4064)
			(stroke
				(width 0.1524)
				(type default)
			)
			(layer "F.SilkS")
		)
		(fp_line
			(start -0.67945 -0.305054)
			(end -0.12065 -0.305054)
			(stroke
				(width 0.1)
				(type default)
			)
			(layer "F.Fab")
		)
		(fp_line
			(start -0.67945 0.3048)
			(end -0.67945 -0.305054)
			(stroke
				(width 0.1)
				(type default)
			)
			(layer "F.Fab")
		)
		(fp_line
			(start -0.12065 -0.305054)
			(end -0.12065 -0.2794)
			(stroke
				(width 0.1)
				(type default)
			)
			(layer "F.Fab")
		)
		(fp_line
			(start -0.12065 -0.2794)
			(end 0.12065 -0.2794)
			(stroke
				(width 0.1)
				(type default)
			)
			(layer "F.Fab")
		)
		(fp_line
			(start -0.12065 0.2794)
			(end -0.12065 0.3048)
			(stroke
				(width 0.1)
				(type default)
			)
			(layer "F.Fab")
		)
		(fp_line
			(start -0.12065 0.3048)
			(end -0.67945 0.3048)
			(stroke
				(width 0.1)
				(type default)
			)
			(layer "F.Fab")
		)
		(fp_line
			(start 0.120396 0.2794)
			(end -0.12065 0.2794)
			(stroke
				(width 0.1)
				(type default)
			)
			(layer "F.Fab")
		)
		(fp_line
			(start 0.120396 0.3048)
			(end 0.120396 0.2794)
			(stroke
				(width 0.1)
				(type default)
			)
			(layer "F.Fab")
		)
		(fp_line
			(start 0.12065 -0.3048)
			(end 0.67945 -0.3048)
			(stroke
				(width 0.1)
				(type default)
			)
			(layer "F.Fab")
		)
		(fp_line
			(start 0.12065 -0.2794)
			(end 0.12065 -0.3048)
			(stroke
				(width 0.1)
				(type default)
			)
			(layer "F.Fab")
		)
		(fp_line
			(start 0.67945 -0.3048)
			(end 0.67945 0.3048)
			(stroke
				(width 0.1)
				(type default)
			)
			(layer "F.Fab")
		)
		(fp_line
			(start 0.67945 0.3048)
			(end 0.120396 0.3048)
			(stroke
				(width 0.1)
				(type default)
			)
			(layer "F.Fab")
		)
		(pad "1" smd circle
			(at -0.40005 0)
			(size 0 0)
			(layers "F.Cu" "F.Mask" "F.Paste")
			(net "PVDD18_S5_P1")
		)
		(pad "2" smd circle
			(at 0.40005 0)
			(size 0 0)
			(layers "F.Cu" "F.Mask" "F.Paste")
			(net "GND")
		)
	)
	(footprint ""
		(layer "F.Cu")
		(at 124.618496 -373.03583 -90)
		(property "Reference" "C1530"
			(at 0 0 270)
			(layer "F.SilkS")
			(hide yes)
			(effects
				(font
					(size 1.27 1.27)
				)
			)
		)
		(property "Value" ""
			(at 0 0 270)
			(layer "F.Fab")
			(effects
				(font
					(size 1.27 1.27)
				)
			)
		)
		(duplicate_pad_numbers_are_jumpers no)
		(fp_line
			(start -0.299974 0.150114)
			(end -0.299974 -0.150114)
			(stroke
				(width 0.1)
				(type default)
			)
			(layer "F.Fab")
		)
		(fp_line
			(start 0.299974 0.150114)
			(end -0.299974 0.150114)
			(stroke
				(width 0.1)
				(type default)
			)
			(layer "F.Fab")
		)
		(fp_line
			(start -0.299974 -0.150114)
			(end 0.299974 -0.150114)
			(stroke
				(width 0.1)
				(type default)
			)
			(layer "F.Fab")
		)
		(fp_line
			(start 0.299974 -0.150114)
			(end 0.299974 0.150114)
			(stroke
				(width 0.1)
				(type default)
			)
			(layer "F.Fab")
		)
		(pad "1" smd rect
			(at -0.2667 0 270)
			(size 0.3048 0.381)
			(layers "F.Cu" "F.Mask" "F.Paste")
			(net "P5E_CPU1_P3_TX_C_DN<8>")
		)
		(pad "2" smd rect
			(at 0.2667 0 270)
			(size 0.3048 0.381)
			(layers "F.Cu" "F.Mask" "F.Paste")
			(net "P5E_CPU1_P3_TX_DN<8>")
		)
	)
)
